# S9S_MB_2U (Grand Teton) — schematic netlist excerpt (pin names and nets, part order shuffled) for the footprints in the layout excerpt that follows; sources: Cadence DE-HDL packaged netlist, KiCad conversion of 03242023_DA0F0TMBIJ0_F0T_Motherboard_J_brd_V01_OCP.brd

R2347  Q_RES  0 5% CHIP  pkg 0402LF  page 215 : A = FM_REMOTE_DEBUG_DET_R ; B = FM_REMOTE_DEBUG_DET
R1201  Q_RES  49.9 1% CHIP  pkg 0402LF  page 182 : A = FM_PCH_TRIGGER1_N ; B = FM_PCH_TRIGGER1_R_N

(kicad_pcb
	(version 20260206)
	(generator "pcbnew")
	(generator_version "10.0")
	(general
		(thickness 1.6)
		(legacy_teardrops no)
	)
	(paper "A4")
	(title_block
		(title "03242023_DA0F0TMBIJ0_F0T_Motherboard_J_brd_V01_OCP.brd")
		(comment 1 "Grand Teton / footprints 5340-5341 of 6105")
	)
	(layers
		(0 "F.Cu" signal "TOP")
		(4 "In1.Cu" signal "GND")
		(6 "In2.Cu" signal "IN1")
		(8 "In3.Cu" signal "GND1")
		(10 "In4.Cu" signal "IN2")
		(12 "In5.Cu" signal "GND2")
		(14 "In6.Cu" signal "IN3")
		(16 "In7.Cu" signal "GND3")
		(18 "In8.Cu" signal "VCC")
		(20 "In9.Cu" signal "VCC1")
		(22 "In10.Cu" signal "GND4")
		(24 "In11.Cu" signal "IN4")
		(26 "In12.Cu" signal "GND5")
		(28 "In13.Cu" signal "IN5")
		(30 "In14.Cu" signal "GND6")
		(32 "In15.Cu" signal "IN6")
		(34 "In16.Cu" signal "GND7")
		(2 "B.Cu" signal "BOTTOM")
		(9 "F.Adhes" user "F.Adhesive")
		(11 "B.Adhes" user "B.Adhesive")
		(13 "F.Paste" user "Package Geometry/Pastemask Top")
		(15 "B.Paste" user "Package Geometry/Pastemask Bottom")
		(5 "F.SilkS" user "Ref Des/Silkscreen Top")
		(7 "B.SilkS" user "Ref Des/Silkscreen Bottom")
		(1 "F.Mask" user "Board Geometry/Soldermask Top")
		(3 "B.Mask" user "Board Geometry/Soldermask Bottom")
		(17 "Dwgs.User" user "User.Drawings")
		(19 "Cmts.User" user "User.Comments")
		(21 "Eco1.User" user "User.Eco1")
		(23 "Eco2.User" user "User.Eco2")
		(25 "Edge.Cuts" user "Board Geometry/Outline")
		(27 "Margin" user)
		(31 "F.CrtYd" user "Package Geometry/Place Bound Top")
		(29 "B.CrtYd" user "Package Geometry/Place Bound Bottom")
		(35 "F.Fab" user "Ref Des/Assembly Top")
		(33 "B.Fab" user "Ref Des/Assembly Bottom")
	)
	(footprint ""
		(layer "B.Cu")
		(at 197.41388 -106.225848)
		(property "Reference" "R2347"
			(at 0 0 0)
			(layer "B.SilkS")
			(hide yes)
			(effects
				(font
					(size 1.27 1.27)
				)
				(justify mirror)
			)
		)
		(property "Value" ""
			(at 0 0 0)
			(layer "B.Fab")
			(effects
				(font
					(size 1.27 1.27)
				)
				(justify mirror)
			)
		)
		(duplicate_pad_numbers_are_jumpers no)
		(fp_line
			(start -0.7874 -0.4064)
			(end -0.7874 0.4064)
			(stroke
				(width 0.1524)
				(type default)
			)
			(layer "B.SilkS")
		)
		(fp_line
			(start -0.7874 0.4064)
			(end 0.7874 0.4064)
			(stroke
				(width 0.1524)
				(type default)
			)
			(layer "B.SilkS")
		)
		(fp_line
			(start 0.7874 -0.4064)
			(end -0.7874 -0.4064)
			(stroke
				(width 0.1524)
				(type default)
			)
			(layer "B.SilkS")
		)
		(fp_line
			(start 0.7874 0.4064)
			(end 0.7874 -0.4064)
			(stroke
				(width 0.1524)
				(type default)
			)
			(layer "B.SilkS")
		)
		(fp_line
			(start -0.67945 -0.3048)
			(end -0.67945 0.3048)
			(stroke
				(width 0.1)
				(type default)
			)
			(layer "B.Fab")
		)
		(fp_line
			(start -0.67945 0.3048)
			(end -0.120396 0.3048)
			(stroke
				(width 0.1)
				(type default)
			)
			(layer "B.Fab")
		)
		(fp_line
			(start -0.12065 -0.3048)
			(end -0.67945 -0.3048)
			(stroke
				(width 0.1)
				(type default)
			)
			(layer "B.Fab")
		)
		(fp_line
			(start -0.12065 -0.2794)
			(end -0.12065 -0.3048)
			(stroke
				(width 0.1)
				(type default)
			)
			(layer "B.Fab")
		)
		(fp_line
			(start -0.120396 0.2794)
			(end 0.12065 0.2794)
			(stroke
				(width 0.1)
				(type default)
			)
			(layer "B.Fab")
		)
		(fp_line
			(start -0.120396 0.3048)
			(end -0.120396 0.2794)
			(stroke
				(width 0.1)
				(type default)
			)
			(layer "B.Fab")
		)
		(fp_line
			(start 0.12065 -0.305054)
			(end 0.12065 -0.2794)
			(stroke
				(width 0.1)
				(type default)
			)
			(layer "B.Fab")
		)
		(fp_line
			(start 0.12065 -0.2794)
			(end -0.12065 -0.2794)
			(stroke
				(width 0.1)
				(type default)
			)
			(layer "B.Fab")
		)
		(fp_line
			(start 0.12065 0.2794)
			(end 0.12065 0.3048)
			(stroke
				(width 0.1)
				(type default)
			)
			(layer "B.Fab")
		)
		(fp_line
			(start 0.12065 0.3048)
			(end 0.67945 0.3048)
			(stroke
				(width 0.1)
				(type default)
			)
			(layer "B.Fab")
		)
		(fp_line
			(start 0.67945 -0.305054)
			(end 0.12065 -0.305054)
			(stroke
				(width 0.1)
				(type default)
			)
			(layer "B.Fab")
		)
		(fp_line
			(start 0.67945 0.3048)
			(end 0.67945 -0.305054)
			(stroke
				(width 0.1)
				(type default)
			)
			(layer "B.Fab")
		)
		(pad "1" smd circle
			(at 0.40005 0 180)
			(size 0 0)
			(layers "B.Cu" "B.Mask" "B.Paste")
			(net "FM_REMOTE_DEBUG_DET_R")
		)
		(pad "2" smd circle
			(at -0.40005 0 180)
			(size 0 0)
			(layers "B.Cu" "B.Mask" "B.Paste")
			(net "FM_REMOTE_DEBUG_DET")
		)
	)
	(footprint ""
		(layer "B.Cu")
		(at 315.110622 -55.235348 180)
		(property "Reference" "R1201"
			(at 0 0 0)
			(layer "B.SilkS")
			(hide yes)
			(effects
				(font
					(size 1.27 1.27)
				)
				(justify mirror)
			)
		)
		(property "Value" ""
			(at 0 0 0)
			(layer "B.Fab")
			(effects
				(font
					(size 1.27 1.27)
				)
				(justify mirror)
			)
		)
		(duplicate_pad_numbers_are_jumpers no)
		(fp_line
			(start 0.7874 0.4064)
			(end 0.7874 -0.4064)
			(stroke
				(width 0.1524)
				(type default)
			)
			(layer "B.SilkS")
		)
		(fp_line
			(start 0.7874 -0.4064)
			(end -0.7874 -0.4064)
			(stroke
				(width 0.1524)
				(type default)
			)
			(layer "B.SilkS")
		)
		(fp_line
			(start -0.7874 0.4064)
			(end 0.7874 0.4064)
			(stroke
				(width 0.1524)
				(type default)
			)
			(layer "B.SilkS")
		)
		(fp_line
			(start -0.7874 -0.4064)
			(end -0.7874 0.4064)
			(stroke
				(width 0.1524)
				(type default)
			)
			(layer "B.SilkS")
		)
		(fp_line
			(start 0.67945 0.3048)
			(end 0.67945 -0.305054)
			(stroke
				(width 0.1)
				(type default)
			)
			(layer "B.Fab")
		)
		(fp_line
			(start 0.67945 -0.305054)
			(end 0.12065 -0.305054)
			(stroke
				(width 0.1)
				(type default)
			)
			(layer "B.Fab")
		)
		(fp_line
			(start 0.12065 0.3048)
			(end 0.67945 0.3048)
			(stroke
				(width 0.1)
				(type default)
			)
			(layer "B.Fab")
		)
		(fp_line
			(start 0.12065 0.2794)
			(end 0.12065 0.3048)
			(stroke
				(width 0.1)
				(type default)
			)
			(layer "B.Fab")
		)
		(fp_line
			(start 0.12065 -0.2794)
			(end -0.12065 -0.2794)
			(stroke
				(width 0.1)
				(type default)
			)
			(layer "B.Fab")
		)
		(fp_line
			(start 0.12065 -0.305054)
			(end 0.12065 -0.2794)
			(stroke
				(width 0.1)
				(type default)
			)
			(layer "B.Fab")
		)
		(fp_line
			(start -0.120396 0.3048)
			(end -0.120396 0.2794)
			(stroke
				(width 0.1)
				(type default)
			)
			(layer "B.Fab")
		)
		(fp_line
			(start -0.120396 0.2794)
			(end 0.12065 0.2794)
			(stroke
				(width 0.1)
				(type default)
			)
			(layer "B.Fab")
		)
		(fp_line
			(start -0.12065 -0.2794)
			(end -0.12065 -0.3048)
			(stroke
				(width 0.1)
				(type default)
			)
			(layer "B.Fab")
		)
		(fp_line
			(start -0.12065 -0.3048)
			(end -0.67945 -0.3048)
			(stroke
				(width 0.1)
				(type default)
			)
			(layer "B.Fab")
		)
		(fp_line
			(start -0.67945 0.3048)
			(end -0.120396 0.3048)
			(stroke
				(width 0.1)
				(type default)
			)
			(layer "B.Fab")
		)
		(fp_line
			(start -0.67945 -0.3048)
			(end -0.67945 0.3048)
			(stroke
				(width 0.1)
				(type default)
			)
			(layer "B.Fab")
		)
		(pad "1" smd circle
			(at 0.40005 0)
			(size 0 0)
			(layers "B.Cu" "B.Mask" "B.Paste")
			(net "FM_PCH_TRIGGER1_N")
		)
		(pad "2" smd circle
			(at -0.40005 0)
			(size 0 0)
			(layers "B.Cu" "B.Mask" "B.Paste")
			(net "FM_PCH_TRIGGER1_R_N")
		)
	)
)
